(kicad_pcb
	(version 20260206)
	(generator "pcbnew")
	(generator_version "10.0")
	(general
		(thickness 1.6)
		(legacy_teardrops no)
	)
	(paper "A4")
	(title_block
		(title "01162023_DA0F0TEBIF0_F0T_Expander_BD_F_brd_V02_OCP.brd")
		(comment 1 "Grand Teton / footprints 8597-8603 of 9728")
	)
	(layers
		(0 "F.Cu" signal "TOP")
		(4 "In1.Cu" signal "GND")
		(6 "In2.Cu" signal "VCC")
		(8 "In3.Cu" signal "VCC1")
		(10 "In4.Cu" signal "GND1")
		(12 "In5.Cu" signal "IN1")
		(14 "In6.Cu" signal "GND2")
		(16 "In7.Cu" signal "IN2")
		(18 "In8.Cu" signal "GND3")
		(20 "In9.Cu" signal "IN3")
		(22 "In10.Cu" signal "GND4")
		(24 "In11.Cu" signal "IN4")
		(26 "In12.Cu" signal "GND5")
		(28 "In13.Cu" signal "IN5")
		(30 "In14.Cu" signal "GND6")
		(32 "In15.Cu" signal "IN6")
		(34 "In16.Cu" signal "GND7")
		(2 "B.Cu" signal "BOTTOM")
		(9 "F.Adhes" user "F.Adhesive")
		(11 "B.Adhes" user "B.Adhesive")
		(13 "F.Paste" user "Package Geometry/Pastemask Top")
		(15 "B.Paste" user "Package Geometry/Pastemask Bottom")
		(5 "F.SilkS" user "Ref Des/Silkscreen Top")
		(7 "B.SilkS" user "Ref Des/Silkscreen Bottom")
		(1 "F.Mask" user "Board Geometry/Soldermask Top")
		(3 "B.Mask" user "Board Geometry/Soldermask Bottom")
		(17 "Dwgs.User" user "User.Drawings")
		(19 "Cmts.User" user "User.Comments")
		(21 "Eco1.User" user "User.Eco1")
		(23 "Eco2.User" user "User.Eco2")
		(25 "Edge.Cuts" user "Board Geometry/Outline")
		(27 "Margin" user)
		(31 "F.CrtYd" user "Package Geometry/Place Bound Top")
		(29 "B.CrtYd" user "Package Geometry/Place Bound Bottom")
		(35 "F.Fab" user "Ref Des/Assembly Top")
		(33 "B.Fab" user "Ref Des/Assembly Bottom")
	)
	(footprint ""
		(layer "B.Cu")
		(at 141.793214 -213.905846 90)
		(property "Reference" "C2610"
			(at 0 0 90)
			(layer "B.SilkS")
			(hide yes)
			(effects
				(font
					(size 1.27 1.27)
				)
				(justify mirror)
			)
		)
		(property "Value" ""
			(at 0 0 90)
			(layer "B.Fab")
			(effects
				(font
					(size 1.27 1.27)
				)
				(justify mirror)
			)
		)
		(duplicate_pad_numbers_are_jumpers no)
		(fp_line
			(start 0.7874 -0.4064)
			(end -0.7874 -0.4064)
			(stroke
				(width 0.1524)
				(type default)
			)
			(layer "B.SilkS")
		)
		(fp_line
			(start -0.7874 -0.4064)
			(end -0.7874 0.4064)
			(stroke
				(width 0.1524)
				(type default)
			)
			(layer "B.SilkS")
		)
		(fp_line
			(start 0.7874 0.4064)
			(end 0.7874 -0.4064)
			(stroke
				(width 0.1524)
				(type default)
			)
			(layer "B.SilkS")
		)
		(fp_line
			(start -0.7874 0.4064)
			(end 0.7874 0.4064)
			(stroke
				(width 0.1524)
				(type default)
			)
			(layer "B.SilkS")
		)
		(fp_line
			(start 0.67945 -0.305054)
			(end 0.12065 -0.305054)
			(stroke
				(width 0.1)
				(type default)
			)
			(layer "B.Fab")
		)
		(fp_line
			(start 0.12065 -0.305054)
			(end 0.12065 -0.2794)
			(stroke
				(width 0.1)
				(type default)
			)
			(layer "B.Fab")
		)
		(fp_line
			(start -0.12065 -0.3048)
			(end -0.67945 -0.3048)
			(stroke
				(width 0.1)
				(type default)
			)
			(layer "B.Fab")
		)
		(fp_line
			(start -0.67945 -0.3048)
			(end -0.67945 0.3048)
			(stroke
				(width 0.1)
				(type default)
			)
			(layer "B.Fab")
		)
		(fp_line
			(start 0.12065 -0.2794)
			(end -0.12065 -0.2794)
			(stroke
				(width 0.1)
				(type default)
			)
			(layer "B.Fab")
		)
		(fp_line
			(start -0.12065 -0.2794)
			(end -0.12065 -0.3048)
			(stroke
				(width 0.1)
				(type default)
			)
			(layer "B.Fab")
		)
		(fp_line
			(start 0.12065 0.2794)
			(end 0.12065 0.3048)
			(stroke
				(width 0.1)
				(type default)
			)
			(layer "B.Fab")
		)
		(fp_line
			(start -0.120396 0.2794)
			(end 0.12065 0.2794)
			(stroke
				(width 0.1)
				(type default)
			)
			(layer "B.Fab")
		)
		(fp_line
			(start 0.67945 0.3048)
			(end 0.67945 -0.305054)
			(stroke
				(width 0.1)
				(type default)
			)
			(layer "B.Fab")
		)
		(fp_line
			(start 0.12065 0.3048)
			(end 0.67945 0.3048)
			(stroke
				(width 0.1)
				(type default)
			)
			(layer "B.Fab")
		)
		(fp_line
			(start -0.120396 0.3048)
			(end -0.120396 0.2794)
			(stroke
				(width 0.1)
				(type default)
			)
			(layer "B.Fab")
		)
		(fp_line
			(start -0.67945 0.3048)
			(end -0.120396 0.3048)
			(stroke
				(width 0.1)
				(type default)
			)
			(layer "B.Fab")
		)
		(pad "1" smd circle
			(at 0.40005 0 270)
			(size 0 0)
			(layers "B.Cu" "B.Mask" "B.Paste")
			(net "GND")
		)
		(pad "2" smd circle
			(at -0.40005 0 270)
			(size 0 0)
			(layers "B.Cu" "B.Mask" "B.Paste")
			(net "P3V3_AUX")
		)
	)
	(footprint ""
		(layer "B.Cu")
		(at 63.449962 -288.299906 90)
		(property "Reference" "C2938"
			(at 0 0 90)
			(layer "B.SilkS")
			(hide yes)
			(effects
				(font
					(size 1.27 1.27)
				)
				(justify mirror)
			)
		)
		(property "Value" ""
			(at 0 0 90)
			(layer "B.Fab")
			(effects
				(font
					(size 1.27 1.27)
				)
				(justify mirror)
			)
		)
		(duplicate_pad_numbers_are_jumpers no)
		(fp_line
			(start 0.299974 -0.150114)
			(end -0.299974 -0.150114)
			(stroke
				(width 0.1)
				(type default)
			)
			(layer "B.Fab")
		)
		(fp_line
			(start -0.299974 -0.150114)
			(end -0.299974 0.150114)
			(stroke
				(width 0.1)
				(type default)
			)
			(layer "B.Fab")
		)
		(fp_line
			(start 0.299974 0.150114)
			(end 0.299974 -0.150114)
			(stroke
				(width 0.1)
				(type default)
			)
			(layer "B.Fab")
		)
		(fp_line
			(start -0.299974 0.150114)
			(end 0.299974 0.150114)
			(stroke
				(width 0.1)
				(type default)
			)
			(layer "B.Fab")
		)
		(pad "1" smd rect
			(at 0.2667 0 270)
			(size 0.3048 0.381)
			(layers "B.Cu" "B.Mask" "B.Paste")
			(net "P1V25_PEX0")
		)
		(pad "2" smd rect
			(at -0.2667 0 270)
			(size 0.3048 0.381)
			(layers "B.Cu" "B.Mask" "B.Paste")
			(net "GND")
		)
	)
	(footprint ""
		(layer "B.Cu")
		(at 340.995 -233.553 90)
		(property "Reference" "R3535"
			(at 0 0 90)
			(layer "B.SilkS")
			(hide yes)
			(effects
				(font
					(size 1.27 1.27)
				)
				(justify mirror)
			)
		)
		(property "Value" ""
			(at 0 0 90)
			(layer "B.Fab")
			(effects
				(font
					(size 1.27 1.27)
				)
				(justify mirror)
			)
		)
		(duplicate_pad_numbers_are_jumpers no)
		(fp_line
			(start 0.7874 -0.4064)
			(end -0.7874 -0.4064)
			(stroke
				(width 0.1524)
				(type default)
			)
			(layer "B.SilkS")
		)
		(fp_line
			(start -0.7874 -0.4064)
			(end -0.7874 0.4064)
			(stroke
				(width 0.1524)
				(type default)
			)
			(layer "B.SilkS")
		)
		(fp_line
			(start 0.7874 0.4064)
			(end 0.7874 -0.4064)
			(stroke
				(width 0.1524)
				(type default)
			)
			(layer "B.SilkS")
		)
		(fp_line
			(start -0.7874 0.4064)
			(end 0.7874 0.4064)
			(stroke
				(width 0.1524)
				(type default)
			)
			(layer "B.SilkS")
		)
		(fp_line
			(start 0.67945 -0.305054)
			(end 0.12065 -0.305054)
			(stroke
				(width 0.1)
				(type default)
			)
			(layer "B.Fab")
		)
		(fp_line
			(start 0.12065 -0.305054)
			(end 0.12065 -0.2794)
			(stroke
				(width 0.1)
				(type default)
			)
			(layer "B.Fab")
		)
		(fp_line
			(start -0.12065 -0.3048)
			(end -0.67945 -0.3048)
			(stroke
				(width 0.1)
				(type default)
			)
			(layer "B.Fab")
		)
		(fp_line
			(start -0.67945 -0.3048)
			(end -0.67945 0.3048)
			(stroke
				(width 0.1)
				(type default)
			)
			(layer "B.Fab")
		)
		(fp_line
			(start 0.12065 -0.2794)
			(end -0.12065 -0.2794)
			(stroke
				(width 0.1)
				(type default)
			)
			(layer "B.Fab")
		)
		(fp_line
			(start -0.12065 -0.2794)
			(end -0.12065 -0.3048)
			(stroke
				(width 0.1)
				(type default)
			)
			(layer "B.Fab")
		)
		(fp_line
			(start 0.12065 0.2794)
			(end 0.12065 0.3048)
			(stroke
				(width 0.1)
				(type default)
			)
			(layer "B.Fab")
		)
		(fp_line
			(start -0.120396 0.2794)
			(end 0.12065 0.2794)
			(stroke
				(width 0.1)
				(type default)
			)
			(layer "B.Fab")
		)
		(fp_line
			(start 0.67945 0.3048)
			(end 0.67945 -0.305054)
			(stroke
				(width 0.1)
				(type default)
			)
			(layer "B.Fab")
		)
		(fp_line
			(start 0.12065 0.3048)
			(end 0.67945 0.3048)
			(stroke
				(width 0.1)
				(type default)
			)
			(layer "B.Fab")
		)
		(fp_line
			(start -0.120396 0.3048)
			(end -0.120396 0.2794)
			(stroke
				(width 0.1)
				(type default)
			)
			(layer "B.Fab")
		)
		(fp_line
			(start -0.67945 0.3048)
			(end -0.120396 0.3048)
			(stroke
				(width 0.1)
				(type default)
			)
			(layer "B.Fab")
		)
		(pad "1" smd circle
			(at 0.40005 0 270)
			(size 0 0)
			(layers "B.Cu" "B.Mask" "B.Paste")
			(net "SSD3_PWR_EN_R")
		)
		(pad "2" smd circle
			(at -0.40005 0 270)
			(size 0 0)
			(layers "B.Cu" "B.Mask" "B.Paste")
			(net "SSD3_PWR_EN")
		)
	)
	(footprint ""
		(layer "B.Cu")
		(at 212.09 -196.977 -90)
		(property "Reference" "R1527"
			(at 0 0 90)
			(layer "B.SilkS")
			(hide yes)
			(effects
				(font
					(size 1.27 1.27)
				)
				(justify mirror)
			)
		)
		(property "Value" ""
			(at 0 0 90)
			(layer "B.Fab")
			(effects
				(font
					(size 1.27 1.27)
				)
				(justify mirror)
			)
		)
		(duplicate_pad_numbers_are_jumpers no)
		(fp_line
			(start -0.7874 0.4064)
			(end 0.7874 0.4064)
			(stroke
				(width 0.1524)
				(type default)
			)
			(layer "B.SilkS")
		)
		(fp_line
			(start 0.7874 0.4064)
			(end 0.7874 -0.4064)
			(stroke
				(width 0.1524)
				(type default)
			)
			(layer "B.SilkS")
		)
		(fp_line
			(start -0.7874 -0.4064)
			(end -0.7874 0.4064)
			(stroke
				(width 0.1524)
				(type default)
			)
			(layer "B.SilkS")
		)
		(fp_line
			(start 0.7874 -0.4064)
			(end -0.7874 -0.4064)
			(stroke
				(width 0.1524)
				(type default)
			)
			(layer "B.SilkS")
		)
		(fp_line
			(start -0.67945 0.3048)
			(end -0.120396 0.3048)
			(stroke
				(width 0.1)
				(type default)
			)
			(layer "B.Fab")
		)
		(fp_line
			(start -0.120396 0.3048)
			(end -0.120396 0.2794)
			(stroke
				(width 0.1)
				(type default)
			)
			(layer "B.Fab")
		)
		(fp_line
			(start 0.12065 0.3048)
			(end 0.67945 0.3048)
			(stroke
				(width 0.1)
				(type default)
			)
			(layer "B.Fab")
		)
		(fp_line
			(start 0.67945 0.3048)
			(end 0.67945 -0.305054)
			(stroke
				(width 0.1)
				(type default)
			)
			(layer "B.Fab")
		)
		(fp_line
			(start -0.120396 0.2794)
			(end 0.12065 0.2794)
			(stroke
				(width 0.1)
				(type default)
			)
			(layer "B.Fab")
		)
		(fp_line
			(start 0.12065 0.2794)
			(end 0.12065 0.3048)
			(stroke
				(width 0.1)
				(type default)
			)
			(layer "B.Fab")
		)
		(fp_line
			(start -0.12065 -0.2794)
			(end -0.12065 -0.3048)
			(stroke
				(width 0.1)
				(type default)
			)
			(layer "B.Fab")
		)
		(fp_line
			(start 0.12065 -0.2794)
			(end -0.12065 -0.2794)
			(stroke
				(width 0.1)
				(type default)
			)
			(layer "B.Fab")
		)
		(fp_line
			(start -0.67945 -0.3048)
			(end -0.67945 0.3048)
			(stroke
				(width 0.1)
				(type default)
			)
			(layer "B.Fab")
		)
		(fp_line
			(start -0.12065 -0.3048)
			(end -0.67945 -0.3048)
			(stroke
				(width 0.1)
				(type default)
			)
			(layer "B.Fab")
		)
		(fp_line
			(start 0.12065 -0.305054)
			(end 0.12065 -0.2794)
			(stroke
				(width 0.1)
				(type default)
			)
			(layer "B.Fab")
		)
		(fp_line
			(start 0.67945 -0.305054)
			(end 0.12065 -0.305054)
			(stroke
				(width 0.1)
				(type default)
			)
			(layer "B.Fab")
		)
		(pad "1" smd circle
			(at 0.40005 0 90)
			(size 0 0)
			(layers "B.Cu" "B.Mask" "B.Paste")
			(net "SMB_NIC6_LS_R_SCL")
		)
		(pad "2" smd circle
			(at -0.40005 0 90)
			(size 0 0)
			(layers "B.Cu" "B.Mask" "B.Paste")
			(net "SMB_NIC6_R_SCL")
		)
	)
	(footprint ""
		(layer "B.Cu")
		(at 223.533716 -192.959736 -90)
		(property "Reference" "R1028"
			(at 0 0 90)
			(layer "B.SilkS")
			(hide yes)
			(effects
				(font
					(size 1.27 1.27)
				)
				(justify mirror)
			)
		)
		(property "Value" ""
			(at 0 0 90)
			(layer "B.Fab")
			(effects
				(font
					(size 1.27 1.27)
				)
				(justify mirror)
			)
		)
		(duplicate_pad_numbers_are_jumpers no)
		(fp_line
			(start -0.7874 0.4064)
			(end 0.7874 0.4064)
			(stroke
				(width 0.1524)
				(type default)
			)
			(layer "B.SilkS")
		)
		(fp_line
			(start 0.7874 0.4064)
			(end 0.7874 -0.4064)
			(stroke
				(width 0.1524)
				(type default)
			)
			(layer "B.SilkS")
		)
		(fp_line
			(start -0.7874 -0.4064)
			(end -0.7874 0.4064)
			(stroke
				(width 0.1524)
				(type default)
			)
			(layer "B.SilkS")
		)
		(fp_line
			(start 0.7874 -0.4064)
			(end -0.7874 -0.4064)
			(stroke
				(width 0.1524)
				(type default)
			)
			(layer "B.SilkS")
		)
		(fp_line
			(start -0.67945 0.3048)
			(end -0.120396 0.3048)
			(stroke
				(width 0.1)
				(type default)
			)
			(layer "B.Fab")
		)
		(fp_line
			(start -0.120396 0.3048)
			(end -0.120396 0.2794)
			(stroke
				(width 0.1)
				(type default)
			)
			(layer "B.Fab")
		)
		(fp_line
			(start 0.12065 0.3048)
			(end 0.67945 0.3048)
			(stroke
				(width 0.1)
				(type default)
			)
			(layer "B.Fab")
		)
		(fp_line
			(start 0.67945 0.3048)
			(end 0.67945 -0.305054)
			(stroke
				(width 0.1)
				(type default)
			)
			(layer "B.Fab")
		)
		(fp_line
			(start -0.120396 0.2794)
			(end 0.12065 0.2794)
			(stroke
				(width 0.1)
				(type default)
			)
			(layer "B.Fab")
		)
		(fp_line
			(start 0.12065 0.2794)
			(end 0.12065 0.3048)
			(stroke
				(width 0.1)
				(type default)
			)
			(layer "B.Fab")
		)
		(fp_line
			(start -0.12065 -0.2794)
			(end -0.12065 -0.3048)
			(stroke
				(width 0.1)
				(type default)
			)
			(layer "B.Fab")
		)
		(fp_line
			(start 0.12065 -0.2794)
			(end -0.12065 -0.2794)
			(stroke
				(width 0.1)
				(type default)
			)
			(layer "B.Fab")
		)
		(fp_line
			(start -0.67945 -0.3048)
			(end -0.67945 0.3048)
			(stroke
				(width 0.1)
				(type default)
			)
			(layer "B.Fab")
		)
		(fp_line
			(start -0.12065 -0.3048)
			(end -0.67945 -0.3048)
			(stroke
				(width 0.1)
				(type default)
			)
			(layer "B.Fab")
		)
		(fp_line
			(start 0.12065 -0.305054)
			(end 0.12065 -0.2794)
			(stroke
				(width 0.1)
				(type default)
			)
			(layer "B.Fab")
		)
		(fp_line
			(start 0.67945 -0.305054)
			(end 0.12065 -0.305054)
			(stroke
				(width 0.1)
				(type default)
			)
			(layer "B.Fab")
		)
		(pad "1" smd circle
			(at 0.40005 0 90)
			(size 0 0)
			(layers "B.Cu" "B.Mask" "B.Paste")
			(net "SPI2_DI_BUF")
		)
		(pad "2" smd circle
			(at -0.40005 0 90)
			(size 0 0)
			(layers "B.Cu" "B.Mask" "B.Paste")
			(net "SPI_BIC1_MISO_R2")
		)
	)
	(footprint ""
		(layer "B.Cu")
		(at 65.349882 -303.499774 -90)
		(property "Reference" "C2904"
			(at 0 0 90)
			(layer "B.SilkS")
			(hide yes)
			(effects
				(font
					(size 1.27 1.27)
				)
				(justify mirror)
			)
		)
		(property "Value" ""
			(at 0 0 90)
			(layer "B.Fab")
			(effects
				(font
					(size 1.27 1.27)
				)
				(justify mirror)
			)
		)
		(duplicate_pad_numbers_are_jumpers no)
		(fp_line
			(start -0.299974 0.150114)
			(end 0.299974 0.150114)
			(stroke
				(width 0.1)
				(type default)
			)
			(layer "B.Fab")
		)
		(fp_line
			(start 0.299974 0.150114)
			(end 0.299974 -0.150114)
			(stroke
				(width 0.1)
				(type default)
			)
			(layer "B.Fab")
		)
		(fp_line
			(start -0.299974 -0.150114)
			(end -0.299974 0.150114)
			(stroke
				(width 0.1)
				(type default)
			)
			(layer "B.Fab")
		)
		(fp_line
			(start 0.299974 -0.150114)
			(end -0.299974 -0.150114)
			(stroke
				(width 0.1)
				(type default)
			)
			(layer "B.Fab")
		)
		(pad "1" smd rect
			(at 0.2667 0 90)
			(size 0.3048 0.381)
			(layers "B.Cu" "B.Mask" "B.Paste")
			(net "P1V25_PEX0")
		)
		(pad "2" smd rect
			(at -0.2667 0 90)
			(size 0.3048 0.381)
			(layers "B.Cu" "B.Mask" "B.Paste")
			(net "GND")
		)
	)
	(footprint ""
		(layer "B.Cu")
		(at 353.662488 -220.12148 180)
		(property "Reference" "C2042"
			(at 0 0 0)
			(layer "B.SilkS")
			(hide yes)
			(effects
				(font
					(size 1.27 1.27)
				)
				(justify mirror)
			)
		)
		(property "Value" ""
			(at 0 0 0)
			(layer "B.Fab")
			(effects
				(font
					(size 1.27 1.27)
				)
				(justify mirror)
			)
		)
		(duplicate_pad_numbers_are_jumpers no)
		(fp_line
			(start 0.69215 0.2921)
			(end 0.69215 -0.2921)
			(stroke
				(width 0.1524)
				(type default)
			)
			(layer "B.SilkS")
		)
		(fp_line
			(start 0.69215 -0.2921)
			(end -0.69215 -0.2921)
			(stroke
				(width 0.1524)
				(type default)
			)
			(layer "B.SilkS")
		)
		(fp_line
			(start -0.69215 0.2921)
			(end 0.69215 0.2921)
			(stroke
				(width 0.1524)
				(type default)
			)
			(layer "B.SilkS")
		)
		(fp_line
			(start -0.69215 -0.2921)
			(end -0.69215 0.2921)
			(stroke
				(width 0.1524)
				(type default)
			)
			(layer "B.SilkS")
		)
		(fp_line
			(start 0.51435 0.2794)
			(end 0.51435 -0.2794)
			(stroke
				(width 0.1)
				(type default)
			)
			(layer "B.Fab")
		)
		(fp_line
			(start 0.51435 -0.2794)
			(end -0.51435 -0.2794)
			(stroke
				(width 0.1)
				(type default)
			)
			(layer "B.Fab")
		)
		(fp_line
			(start -0.51435 0.2794)
			(end 0.51435 0.2794)
			(stroke
				(width 0.1)
				(type default)
			)
			(layer "B.Fab")
		)
		(fp_line
			(start -0.51435 -0.2794)
			(end -0.51435 0.2794)
			(stroke
				(width 0.1)
				(type default)
			)
			(layer "B.Fab")
		)
		(pad "1" smd circle
			(at 0.40005 0)
			(size 0 0)
			(layers "B.Cu" "B.Mask" "B.Paste")
			(net "P3V3_FPGA_VCCIO1")
		)
		(pad "2" smd circle
			(at -0.40005 0)
			(size 0 0)
			(layers "B.Cu" "B.Mask" "B.Paste")
			(net "GND")
		)
		(zone
			(layer "B.Cu")
			(hatch none 0.5)
			(connect_pads
				(clearance 0)
			)
			(min_thickness 0.25)
			(keepout
				(tracks not_allowed)
				(vias allowed)
				(pads allowed)
				(copperpour not_allowed)
				(footprints allowed)
			)
			(placement
				(enabled no)
				(sheetname "")
			)
			(fill
				(thermal_gap 0.5)
				(thermal_bridge_width 0.5)
				(island_removal_mode 0)
			)
			(polygon
				(pts
					(xy 353.471988 -220.20911) (xy 353.563428 -220.267276) (xy 353.762818 -220.267276) (xy 353.852988 -220.20911)
					(xy 353.852988 -220.03385) (xy 353.762818 -219.97543) (xy 353.563428 -219.97543) (xy 353.471988 -220.033596)
				)
			)
		)
	)
)
